# BASEBOARD_FAB2 (Tioga Pass) — schematic netlist excerpt (pin names and nets, part order shuffled) for the footprints in the layout excerpt that follows; sources: Cadence DE-HDL packaged netlist, KiCad conversion of Wiwynn_Tioga_Pass_MB.brd

C4F3  CAP_A  1.0UF 6.3V 10% X6S  pkg 0402V  page 193 : A = P1V8_MCP_CPU1 ; B = GND
C5D42  CAP_A  22.0UF 4V 20% X6S  pkg 0603V  page 42 : A = PVCCIN_CPU0 ; B = GND

(kicad_pcb
	(version 20260206)
	(generator "pcbnew")
	(generator_version "10.0")
	(general
		(thickness 1.6)
		(legacy_teardrops no)
	)
	(paper "A4")
	(title_block
		(title "Wiwynn_Tioga_Pass_MB.brd")
		(comment 1 "Tioga Pass / footprints 828-829 of 4770")
	)
	(layers
		(0 "F.Cu" signal "TOP")
		(4 "In1.Cu" signal "L2GND")
		(6 "In2.Cu" signal "L3")
		(8 "In3.Cu" signal "L4GND")
		(10 "In4.Cu" signal "L5")
		(12 "In5.Cu" signal "L6GND")
		(14 "In6.Cu" signal "L7VCC")
		(16 "In7.Cu" signal "L8VCC")
		(18 "In8.Cu" signal "L9GND")
		(20 "In9.Cu" signal "L10")
		(22 "In10.Cu" signal "L11GND")
		(24 "In11.Cu" signal "L12")
		(26 "In12.Cu" signal "L13GND")
		(2 "B.Cu" signal "BOTTOM")
		(9 "F.Adhes" user "F.Adhesive")
		(11 "B.Adhes" user "B.Adhesive")
		(13 "F.Paste" user "Package Geometry/Pastemask Top")
		(15 "B.Paste" user "Package Geometry/Pastemask Bottom")
		(5 "F.SilkS" user "Ref Des/Silkscreen Top")
		(7 "B.SilkS" user "Ref Des/Silkscreen Bottom")
		(1 "F.Mask" user "Board Geometry/Soldermask Top")
		(3 "B.Mask" user "Board Geometry/Soldermask Bottom")
		(17 "Dwgs.User" user "User.Drawings")
		(19 "Cmts.User" user "User.Comments")
		(21 "Eco1.User" user "User.Eco1")
		(23 "Eco2.User" user "User.Eco2")
		(25 "Edge.Cuts" user "Board Geometry/Outline")
		(27 "Margin" user)
		(31 "F.CrtYd" user "Package Geometry/Place Bound Top")
		(29 "B.CrtYd" user "Package Geometry/Place Bound Bottom")
		(35 "F.Fab" user "Ref Des/Assembly Top")
		(33 "B.Fab" user "Ref Des/Assembly Bottom")
	)
	(footprint ""
		(layer "F.Cu")
		(at 261.942072 -73.318116)
		(property "Reference" "C5D42"
			(at 0 0 0)
			(layer "F.SilkS")
			(hide yes)
			(effects
				(font
					(size 1.27 1.27)
				)
			)
		)
		(property "Value" ""
			(at 0 0 0)
			(layer "F.Fab")
			(effects
				(font
					(size 1.27 1.27)
				)
			)
		)
		(duplicate_pad_numbers_are_jumpers no)
		(fp_poly
			(pts
				(xy -0.4953 -0.2032) (xy 0.4953 -0.2032) (xy 0.4953 1.6002) (xy -0.4953 1.6002)
			)
			(stroke
				(width 0)
				(type default)
			)
			(fill no)
			(layer "F.CrtYd")
		)
		(fp_line
			(start -0.4953 -0.2032)
			(end 0.4953 -0.2032)
			(stroke
				(width 0.1)
				(type default)
			)
			(layer "F.Fab")
		)
		(fp_line
			(start -0.4953 1.6002)
			(end -0.4953 -0.2032)
			(stroke
				(width 0.1)
				(type default)
			)
			(layer "F.Fab")
		)
		(fp_line
			(start 0.4953 -0.2032)
			(end 0.4953 1.6002)
			(stroke
				(width 0.1)
				(type default)
			)
			(layer "F.Fab")
		)
		(fp_line
			(start 0.4953 1.6002)
			(end -0.4953 1.6002)
			(stroke
				(width 0.1)
				(type default)
			)
			(layer "F.Fab")
		)
		(pad "1" smd rect
			(at 0 0)
			(size 0.762 0.889)
			(layers "F.Cu" "F.Mask" "F.Paste")
			(net "PVCCIN_CPU0")
		)
		(pad "2" smd rect
			(at 0 1.397)
			(size 0.762 0.889)
			(layers "F.Cu" "F.Mask" "F.Paste")
			(net "GND")
		)
		(zone
			(layer "F.Cu")
			(hatch none 0.5)
			(connect_pads
				(clearance 0)
			)
			(min_thickness 0.25)
			(keepout
				(tracks not_allowed)
				(vias allowed)
				(pads allowed)
				(copperpour not_allowed)
				(footprints allowed)
			)
			(placement
				(enabled no)
				(sheetname "")
			)
			(fill
				(thermal_gap 0.5)
				(thermal_bridge_width 0.5)
				(island_removal_mode 0)
			)
			(polygon
				(pts
					(xy 261.561072 -72.873616) (xy 262.323072 -72.873616) (xy 262.323072 -72.365616) (xy 261.561072 -72.365616)
				)
			)
		)
	)
	(footprint ""
		(layer "F.Cu")
		(at 167.00627 -34.1503 90)
		(property "Reference" "C4F3"
			(at 0 0 90)
			(layer "F.SilkS")
			(hide yes)
			(effects
				(font
					(size 1.27 1.27)
				)
			)
		)
		(property "Value" ""
			(at 0 0 90)
			(layer "F.Fab")
			(effects
				(font
					(size 1.27 1.27)
				)
			)
		)
		(duplicate_pad_numbers_are_jumpers no)
		(fp_poly
			(pts
				(xy 0.3048 -0.1016) (xy 0.3048 0.9906) (xy -0.3048 0.9906) (xy -0.3048 -0.1016)
			)
			(stroke
				(width 0)
				(type default)
			)
			(fill no)
			(layer "F.CrtYd")
		)
		(fp_line
			(start 0.3048 -0.1016)
			(end -0.3048 -0.1016)
			(stroke
				(width 0.1)
				(type default)
			)
			(layer "F.Fab")
		)
		(fp_line
			(start -0.3048 -0.1016)
			(end -0.3048 0.9906)
			(stroke
				(width 0.1)
				(type default)
			)
			(layer "F.Fab")
		)
		(fp_line
			(start 0.3048 0.9906)
			(end 0.3048 -0.1016)
			(stroke
				(width 0.1)
				(type default)
			)
			(layer "F.Fab")
		)
		(fp_line
			(start -0.3048 0.9906)
			(end 0.3048 0.9906)
			(stroke
				(width 0.1)
				(type default)
			)
			(layer "F.Fab")
		)
		(pad "1" smd rect
			(at 0 0 90)
			(size 0.508 0.508)
			(layers "F.Cu" "F.Mask" "F.Paste")
			(net "P1V8_MCP_CPU1")
		)
		(pad "2" smd rect
			(at 0 0.889 90)
			(size 0.508 0.508)
			(layers "F.Cu" "F.Mask" "F.Paste")
			(net "GND")
		)
		(zone
			(layer "F.Cu")
			(hatch none 0.5)
			(connect_pads
				(clearance 0)
			)
			(min_thickness 0.25)
			(keepout
				(tracks allowed)
				(vias not_allowed)
				(pads allowed)
				(copperpour not_allowed)
				(footprints allowed)
			)
			(placement
				(enabled no)
				(sheetname "")
			)
			(fill
				(thermal_gap 0.5)
				(thermal_bridge_width 0.5)
				(island_removal_mode 0)
			)
			(polygon
				(pts
					(xy 167.26027 -33.8963) (xy 167.26027 -34.4043) (xy 167.64127 -34.4043) (xy 167.64127 -33.8963)
				)
			)
		)
		(zone
			(layer "F.Cu")
			(hatch none 0.5)
			(connect_pads
				(clearance 0)
			)
			(min_thickness 0.25)
			(keepout
				(tracks not_allowed)
				(vias allowed)
				(pads allowed)
				(copperpour not_allowed)
				(footprints allowed)
			)
			(placement
				(enabled no)
				(sheetname "")
			)
			(fill
				(thermal_gap 0.5)
				(thermal_bridge_width 0.5)
				(island_removal_mode 0)
			)
			(polygon
				(pts
					(xy 167.64127 -33.8963) (xy 167.64127 -34.4043) (xy 167.26027 -34.4043) (xy 167.26027 -33.8963)
				)
			)
		)
	)
)
